(kicad_pcb
	(version 20260206)
	(generator "pcbnew")
	(generator_version "10.0")
	(general
		(thickness 1.6)
		(legacy_teardrops no)
	)
	(paper "A4")
	(title_block
		(title "01162023_DA0F0TEBIF0_F0T_Expander_BD_F_brd_V02_OCP.brd")
		(comment 1 "Grand Teton / footprints 6489-6493 of 9728")
	)
	(layers
		(0 "F.Cu" signal "TOP")
		(4 "In1.Cu" signal "GND")
		(6 "In2.Cu" signal "VCC")
		(8 "In3.Cu" signal "VCC1")
		(10 "In4.Cu" signal "GND1")
		(12 "In5.Cu" signal "IN1")
		(14 "In6.Cu" signal "GND2")
		(16 "In7.Cu" signal "IN2")
		(18 "In8.Cu" signal "GND3")
		(20 "In9.Cu" signal "IN3")
		(22 "In10.Cu" signal "GND4")
		(24 "In11.Cu" signal "IN4")
		(26 "In12.Cu" signal "GND5")
		(28 "In13.Cu" signal "IN5")
		(30 "In14.Cu" signal "GND6")
		(32 "In15.Cu" signal "IN6")
		(34 "In16.Cu" signal "GND7")
		(2 "B.Cu" signal "BOTTOM")
		(9 "F.Adhes" user "F.Adhesive")
		(11 "B.Adhes" user "B.Adhesive")
		(13 "F.Paste" user "Package Geometry/Pastemask Top")
		(15 "B.Paste" user "Package Geometry/Pastemask Bottom")
		(5 "F.SilkS" user "Ref Des/Silkscreen Top")
		(7 "B.SilkS" user "Ref Des/Silkscreen Bottom")
		(1 "F.Mask" user "Board Geometry/Soldermask Top")
		(3 "B.Mask" user "Board Geometry/Soldermask Bottom")
		(17 "Dwgs.User" user "User.Drawings")
		(19 "Cmts.User" user "User.Comments")
		(21 "Eco1.User" user "User.Eco1")
		(23 "Eco2.User" user "User.Eco2")
		(25 "Edge.Cuts" user "Board Geometry/Outline")
		(27 "Margin" user)
		(31 "F.CrtYd" user "Package Geometry/Place Bound Top")
		(29 "B.CrtYd" user "Package Geometry/Place Bound Bottom")
		(35 "F.Fab" user "Ref Des/Assembly Top")
		(33 "B.Fab" user "Ref Des/Assembly Bottom")
	)
	(footprint ""
		(layer "F.Cu")
		(at 318.31026 -63.652146 180)
		(property "Reference" "R6007"
			(at 0 0 180)
			(layer "F.SilkS")
			(hide yes)
			(effects
				(font
					(size 1.27 1.27)
				)
			)
		)
		(property "Value" ""
			(at 0 0 180)
			(layer "F.Fab")
			(effects
				(font
					(size 1.27 1.27)
				)
			)
		)
		(duplicate_pad_numbers_are_jumpers no)
		(fp_line
			(start 0.7874 0.4064)
			(end -0.7874 0.4064)
			(stroke
				(width 0.1524)
				(type default)
			)
			(layer "F.SilkS")
		)
		(fp_line
			(start 0.7874 -0.4064)
			(end 0.7874 0.4064)
			(stroke
				(width 0.1524)
				(type default)
			)
			(layer "F.SilkS")
		)
		(fp_line
			(start -0.7874 0.4064)
			(end -0.7874 -0.4064)
			(stroke
				(width 0.1524)
				(type default)
			)
			(layer "F.SilkS")
		)
		(fp_line
			(start -0.7874 -0.4064)
			(end 0.7874 -0.4064)
			(stroke
				(width 0.1524)
				(type default)
			)
			(layer "F.SilkS")
		)
		(fp_line
			(start 0.67945 0.3048)
			(end 0.120396 0.3048)
			(stroke
				(width 0.1)
				(type default)
			)
			(layer "F.Fab")
		)
		(fp_line
			(start 0.67945 -0.3048)
			(end 0.67945 0.3048)
			(stroke
				(width 0.1)
				(type default)
			)
			(layer "F.Fab")
		)
		(fp_line
			(start 0.12065 -0.2794)
			(end 0.12065 -0.3048)
			(stroke
				(width 0.1)
				(type default)
			)
			(layer "F.Fab")
		)
		(fp_line
			(start 0.12065 -0.3048)
			(end 0.67945 -0.3048)
			(stroke
				(width 0.1)
				(type default)
			)
			(layer "F.Fab")
		)
		(fp_line
			(start 0.120396 0.3048)
			(end 0.120396 0.2794)
			(stroke
				(width 0.1)
				(type default)
			)
			(layer "F.Fab")
		)
		(fp_line
			(start 0.120396 0.2794)
			(end -0.12065 0.2794)
			(stroke
				(width 0.1)
				(type default)
			)
			(layer "F.Fab")
		)
		(fp_line
			(start -0.12065 0.3048)
			(end -0.67945 0.3048)
			(stroke
				(width 0.1)
				(type default)
			)
			(layer "F.Fab")
		)
		(fp_line
			(start -0.12065 0.2794)
			(end -0.12065 0.3048)
			(stroke
				(width 0.1)
				(type default)
			)
			(layer "F.Fab")
		)
		(fp_line
			(start -0.12065 -0.2794)
			(end 0.12065 -0.2794)
			(stroke
				(width 0.1)
				(type default)
			)
			(layer "F.Fab")
		)
		(fp_line
			(start -0.12065 -0.305054)
			(end -0.12065 -0.2794)
			(stroke
				(width 0.1)
				(type default)
			)
			(layer "F.Fab")
		)
		(fp_line
			(start -0.67945 0.3048)
			(end -0.67945 -0.305054)
			(stroke
				(width 0.1)
				(type default)
			)
			(layer "F.Fab")
		)
		(fp_line
			(start -0.67945 -0.305054)
			(end -0.12065 -0.305054)
			(stroke
				(width 0.1)
				(type default)
			)
			(layer "F.Fab")
		)
		(pad "1" smd circle
			(at -0.40005 0 180)
			(size 0 0)
			(layers "F.Cu" "F.Mask" "F.Paste")
			(net "P5V_AUX")
		)
		(pad "2" smd circle
			(at 0.40005 0 180)
			(size 0 0)
			(layers "F.Cu" "F.Mask" "F.Paste")
			(net "P12V_SSD11_PG_G2")
		)
	)
	(footprint ""
		(layer "F.Cu")
		(at 240.320576 -26.666444 -90)
		(property "Reference" "R4069"
			(at 0 0 270)
			(layer "F.SilkS")
			(hide yes)
			(effects
				(font
					(size 1.27 1.27)
				)
			)
		)
		(property "Value" ""
			(at 0 0 270)
			(layer "F.Fab")
			(effects
				(font
					(size 1.27 1.27)
				)
			)
		)
		(duplicate_pad_numbers_are_jumpers no)
		(fp_line
			(start -0.7874 0.4064)
			(end -0.7874 -0.4064)
			(stroke
				(width 0.1524)
				(type default)
			)
			(layer "F.SilkS")
		)
		(fp_line
			(start 0.7874 0.4064)
			(end -0.7874 0.4064)
			(stroke
				(width 0.1524)
				(type default)
			)
			(layer "F.SilkS")
		)
		(fp_line
			(start -0.7874 -0.4064)
			(end 0.7874 -0.4064)
			(stroke
				(width 0.1524)
				(type default)
			)
			(layer "F.SilkS")
		)
		(fp_line
			(start 0.7874 -0.4064)
			(end 0.7874 0.4064)
			(stroke
				(width 0.1524)
				(type default)
			)
			(layer "F.SilkS")
		)
		(fp_line
			(start -0.67945 0.3048)
			(end -0.67945 -0.305054)
			(stroke
				(width 0.1)
				(type default)
			)
			(layer "F.Fab")
		)
		(fp_line
			(start -0.12065 0.3048)
			(end -0.67945 0.3048)
			(stroke
				(width 0.1)
				(type default)
			)
			(layer "F.Fab")
		)
		(fp_line
			(start 0.120396 0.3048)
			(end 0.120396 0.2794)
			(stroke
				(width 0.1)
				(type default)
			)
			(layer "F.Fab")
		)
		(fp_line
			(start 0.67945 0.3048)
			(end 0.120396 0.3048)
			(stroke
				(width 0.1)
				(type default)
			)
			(layer "F.Fab")
		)
		(fp_line
			(start -0.12065 0.2794)
			(end -0.12065 0.3048)
			(stroke
				(width 0.1)
				(type default)
			)
			(layer "F.Fab")
		)
		(fp_line
			(start 0.120396 0.2794)
			(end -0.12065 0.2794)
			(stroke
				(width 0.1)
				(type default)
			)
			(layer "F.Fab")
		)
		(fp_line
			(start -0.12065 -0.2794)
			(end 0.12065 -0.2794)
			(stroke
				(width 0.1)
				(type default)
			)
			(layer "F.Fab")
		)
		(fp_line
			(start 0.12065 -0.2794)
			(end 0.12065 -0.3048)
			(stroke
				(width 0.1)
				(type default)
			)
			(layer "F.Fab")
		)
		(fp_line
			(start 0.12065 -0.3048)
			(end 0.67945 -0.3048)
			(stroke
				(width 0.1)
				(type default)
			)
			(layer "F.Fab")
		)
		(fp_line
			(start 0.67945 -0.3048)
			(end 0.67945 0.3048)
			(stroke
				(width 0.1)
				(type default)
			)
			(layer "F.Fab")
		)
		(fp_line
			(start -0.67945 -0.305054)
			(end -0.12065 -0.305054)
			(stroke
				(width 0.1)
				(type default)
			)
			(layer "F.Fab")
		)
		(fp_line
			(start -0.12065 -0.305054)
			(end -0.12065 -0.2794)
			(stroke
				(width 0.1)
				(type default)
			)
			(layer "F.Fab")
		)
		(pad "1" smd circle
			(at -0.40005 0 270)
			(size 0 0)
			(layers "F.Cu" "F.Mask" "F.Paste")
			(net "PRSNT_SSD8_R_N")
		)
		(pad "2" smd circle
			(at 0.40005 0 270)
			(size 0 0)
			(layers "F.Cu" "F.Mask" "F.Paste")
			(net "PRSNT_SSD8_N")
		)
	)
	(footprint ""
		(layer "F.Cu")
		(at 216.945972 -46.4439 180)
		(property "Reference" "U62"
			(at 0.080772 -2.45237 0)
			(unlocked yes)
			(layer "F.SilkS")
			(effects
				(font
					(size 0.7874 0.5842)
					(thickness 0.1524)
				)
			)
		)
		(property "Value" ""
			(at 0 0 180)
			(layer "F.Fab")
			(effects
				(font
					(size 1.27 1.27)
				)
			)
		)
		(duplicate_pad_numbers_are_jumpers no)
		(fp_line
			(start 1.500124 1.500124)
			(end 1.004062 1.500124)
			(stroke
				(width 0.1524)
				(type default)
			)
			(layer "F.SilkS")
		)
		(fp_line
			(start 1.500124 1.004062)
			(end 1.500124 1.500124)
			(stroke
				(width 0.1524)
				(type default)
			)
			(layer "F.SilkS")
		)
		(fp_line
			(start 1.500124 -1.500124)
			(end 1.500124 -1.004062)
			(stroke
				(width 0.1524)
				(type default)
			)
			(layer "F.SilkS")
		)
		(fp_line
			(start 1.004062 -1.500124)
			(end 1.500124 -1.500124)
			(stroke
				(width 0.1524)
				(type default)
			)
			(layer "F.SilkS")
		)
		(fp_line
			(start -1.004062 1.500124)
			(end -1.500124 1.500124)
			(stroke
				(width 0.1524)
				(type default)
			)
			(layer "F.SilkS")
		)
		(fp_line
			(start -1.500124 1.500124)
			(end -1.500124 1.004062)
			(stroke
				(width 0.1524)
				(type default)
			)
			(layer "F.SilkS")
		)
		(fp_line
			(start -1.500124 -1.004062)
			(end -1.500124 -1.500124)
			(stroke
				(width 0.1524)
				(type default)
			)
			(layer "F.SilkS")
		)
		(fp_line
			(start -1.500124 -1.500124)
			(end -1.004062 -1.500124)
			(stroke
				(width 0.1524)
				(type default)
			)
			(layer "F.SilkS")
		)
		(fp_poly
			(pts
				(xy -1.697482 -2.477516) (xy -2.416048 -1.759204) (xy -1.338326 -1.400048)
			)
			(stroke
				(width 0)
				(type default)
			)
			(fill yes)
			(layer "F.SilkS")
		)
		(fp_line
			(start 1.500124 1.500124)
			(end -1.500124 1.500124)
			(stroke
				(width 0.1)
				(type default)
			)
			(layer "F.Fab")
		)
		(fp_line
			(start 1.500124 -1.500124)
			(end 1.500124 1.500124)
			(stroke
				(width 0.1)
				(type default)
			)
			(layer "F.Fab")
		)
		(fp_line
			(start -1.500124 1.500124)
			(end -1.500124 -1.500124)
			(stroke
				(width 0.1)
				(type default)
			)
			(layer "F.Fab")
		)
		(fp_line
			(start -1.500124 -1.500124)
			(end 1.500124 -1.500124)
			(stroke
				(width 0.1)
				(type default)
			)
			(layer "F.Fab")
		)
		(fp_poly
			(pts
				(xy -2.847848 -1.258062) (xy -2.847848 -0.242062) (xy -1.831848 -0.750062)
			)
			(stroke
				(width 0)
				(type default)
			)
			(fill yes)
			(layer "F.Fab")
		)
		(pad "1" smd rect
			(at -1.400048 -0.750062 90)
			(size 0.2286 0.6096)
			(layers "F.Cu" "F.Mask" "F.Paste")
			(net "SSD7_ADC_A1")
		)
		(pad "2" smd rect
			(at -1.400048 -0.249936 90)
			(size 0.2286 0.6096)
			(layers "F.Cu" "F.Mask" "F.Paste")
			(net "SSD7_ADC_A0")
		)
		(pad "3" smd rect
			(at -1.400048 0.249936 90)
			(size 0.2286 0.6096)
			(layers "F.Cu" "F.Mask" "F.Paste")
			(net "SSD7_ADC_ALERT_N")
		)
		(pad "4" smd rect
			(at -1.400048 0.750062 90)
			(size 0.2286 0.6096)
			(layers "F.Cu" "F.Mask" "F.Paste")
			(net "SMB_SSD7_ADC_SDA")
		)
		(pad "5" smd rect
			(at -0.750062 1.400048 180)
			(size 0.2286 0.6096)
			(layers "F.Cu" "F.Mask" "F.Paste")
			(net "SMB_SSD7_ADC_SCL")
		)
		(pad "6" smd rect
			(at -0.249936 1.400048 180)
			(size 0.2286 0.6096)
			(layers "F.Cu" "F.Mask" "F.Paste")
			(net "Net_8720")
		)
		(pad "7" smd rect
			(at 0.249936 1.400048 180)
			(size 0.2286 0.6096)
			(layers "F.Cu" "F.Mask" "F.Paste")
			(net "Net_8719")
		)
		(pad "8" smd rect
			(at 0.750062 1.400048 180)
			(size 0.2286 0.6096)
			(layers "F.Cu" "F.Mask" "F.Paste")
			(net "Net_8718")
		)
		(pad "9" smd rect
			(at 1.400048 0.750062 90)
			(size 0.2286 0.6096)
			(layers "F.Cu" "F.Mask" "F.Paste")
			(net "P3V3_AUX")
		)
		(pad "10" smd rect
			(at 1.400048 0.249936 90)
			(size 0.2286 0.6096)
			(layers "F.Cu" "F.Mask" "F.Paste")
			(net "GND")
		)
		(pad "11" smd rect
			(at 1.400048 -0.249936 90)
			(size 0.2286 0.6096)
			(layers "F.Cu" "F.Mask" "F.Paste")
			(net "P12V_SSD7_R")
		)
		(pad "12" smd rect
			(at 1.400048 -0.750062 90)
			(size 0.2286 0.6096)
			(layers "F.Cu" "F.Mask" "F.Paste")
			(net "P12V_SSD7_VIN_N")
		)
		(pad "13" smd rect
			(at 0.750062 -1.400048 180)
			(size 0.2286 0.6096)
			(layers "F.Cu" "F.Mask" "F.Paste")
			(net "P12V_SSD7_VIN_P")
		)
		(pad "14" smd rect
			(at 0.249936 -1.400048 180)
			(size 0.2286 0.6096)
			(layers "F.Cu" "F.Mask" "F.Paste")
			(net "Net_8717")
		)
		(pad "15" smd rect
			(at -0.249936 -1.400048 180)
			(size 0.2286 0.6096)
			(layers "F.Cu" "F.Mask" "F.Paste")
			(net "Net_8716")
		)
		(pad "16" smd rect
			(at -0.750062 -1.400048 180)
			(size 0.2286 0.6096)
			(layers "F.Cu" "F.Mask" "F.Paste")
			(net "Net_8715")
		)
		(pad "TH" smd rect
			(at 0 0 180)
			(size 1.7018 1.7018)
			(layers "F.Cu" "F.Mask" "F.Paste")
			(net "GND")
		)
		(zone
			(layer "F.Cu")
			(hatch none 0.5)
			(connect_pads
				(clearance 0)
			)
			(min_thickness 0.25)
			(keepout
				(tracks not_allowed)
				(vias allowed)
				(pads allowed)
				(copperpour not_allowed)
				(footprints allowed)
			)
			(placement
				(enabled no)
				(sheetname "")
			)
			(fill
				(thermal_gap 0.5)
				(thermal_bridge_width 0.5)
				(island_removal_mode 0)
			)
			(polygon
				(pts
					(xy 217.99042 -46.4185) (xy 217.99042 -45.399452) (xy 215.901524 -45.399452) (xy 215.901524 -47.488348)
					(xy 217.99042 -47.488348) (xy 217.99042 -46.4439) (xy 217.847672 -46.4439) (xy 217.847672 -47.3456)
					(xy 216.044272 -47.3456) (xy 216.044272 -45.5422) (xy 217.847672 -45.5422) (xy 217.847672 -46.4185)
				)
			)
		)
	)
	(footprint ""
		(layer "F.Cu")
		(at 339.718396 -120.53824 180)
		(property "Reference" "R6037"
			(at 0 0 180)
			(layer "F.SilkS")
			(hide yes)
			(effects
				(font
					(size 1.27 1.27)
				)
			)
		)
		(property "Value" ""
			(at 0 0 180)
			(layer "F.Fab")
			(effects
				(font
					(size 1.27 1.27)
				)
			)
		)
		(duplicate_pad_numbers_are_jumpers no)
		(fp_line
			(start 0.7874 0.4064)
			(end -0.7874 0.4064)
			(stroke
				(width 0.1524)
				(type default)
			)
			(layer "F.SilkS")
		)
		(fp_line
			(start 0.7874 -0.4064)
			(end 0.7874 0.4064)
			(stroke
				(width 0.1524)
				(type default)
			)
			(layer "F.SilkS")
		)
		(fp_line
			(start -0.7874 0.4064)
			(end -0.7874 -0.4064)
			(stroke
				(width 0.1524)
				(type default)
			)
			(layer "F.SilkS")
		)
		(fp_line
			(start -0.7874 -0.4064)
			(end 0.7874 -0.4064)
			(stroke
				(width 0.1524)
				(type default)
			)
			(layer "F.SilkS")
		)
		(fp_line
			(start 0.67945 0.3048)
			(end 0.120396 0.3048)
			(stroke
				(width 0.1)
				(type default)
			)
			(layer "F.Fab")
		)
		(fp_line
			(start 0.67945 -0.3048)
			(end 0.67945 0.3048)
			(stroke
				(width 0.1)
				(type default)
			)
			(layer "F.Fab")
		)
		(fp_line
			(start 0.12065 -0.2794)
			(end 0.12065 -0.3048)
			(stroke
				(width 0.1)
				(type default)
			)
			(layer "F.Fab")
		)
		(fp_line
			(start 0.12065 -0.3048)
			(end 0.67945 -0.3048)
			(stroke
				(width 0.1)
				(type default)
			)
			(layer "F.Fab")
		)
		(fp_line
			(start 0.120396 0.3048)
			(end 0.120396 0.2794)
			(stroke
				(width 0.1)
				(type default)
			)
			(layer "F.Fab")
		)
		(fp_line
			(start 0.120396 0.2794)
			(end -0.12065 0.2794)
			(stroke
				(width 0.1)
				(type default)
			)
			(layer "F.Fab")
		)
		(fp_line
			(start -0.12065 0.3048)
			(end -0.67945 0.3048)
			(stroke
				(width 0.1)
				(type default)
			)
			(layer "F.Fab")
		)
		(fp_line
			(start -0.12065 0.2794)
			(end -0.12065 0.3048)
			(stroke
				(width 0.1)
				(type default)
			)
			(layer "F.Fab")
		)
		(fp_line
			(start -0.12065 -0.2794)
			(end 0.12065 -0.2794)
			(stroke
				(width 0.1)
				(type default)
			)
			(layer "F.Fab")
		)
		(fp_line
			(start -0.12065 -0.305054)
			(end -0.12065 -0.2794)
			(stroke
				(width 0.1)
				(type default)
			)
			(layer "F.Fab")
		)
		(fp_line
			(start -0.67945 0.3048)
			(end -0.67945 -0.305054)
			(stroke
				(width 0.1)
				(type default)
			)
			(layer "F.Fab")
		)
		(fp_line
			(start -0.67945 -0.305054)
			(end -0.12065 -0.305054)
			(stroke
				(width 0.1)
				(type default)
			)
			(layer "F.Fab")
		)
		(pad "1" smd circle
			(at -0.40005 0 180)
			(size 0 0)
			(layers "F.Cu" "F.Mask" "F.Paste")
			(net "P5V_AUX")
		)
		(pad "2" smd circle
			(at 0.40005 0 180)
			(size 0 0)
			(layers "F.Cu" "F.Mask" "F.Paste")
			(net "P3V3_NIC5_PG_G2")
		)
	)
	(footprint ""
		(layer "F.Cu")
		(at 117.958362 -131.218686 180)
		(property "Reference" "R2774"
			(at 0 0 180)
			(layer "F.SilkS")
			(hide yes)
			(effects
				(font
					(size 1.27 1.27)
				)
			)
		)
		(property "Value" ""
			(at 0 0 180)
			(layer "F.Fab")
			(effects
				(font
					(size 1.27 1.27)
				)
			)
		)
		(duplicate_pad_numbers_are_jumpers no)
		(fp_line
			(start 0.7874 0.4064)
			(end -0.7874 0.4064)
			(stroke
				(width 0.1524)
				(type default)
			)
			(layer "F.SilkS")
		)
		(fp_line
			(start 0.7874 -0.4064)
			(end 0.7874 0.4064)
			(stroke
				(width 0.1524)
				(type default)
			)
			(layer "F.SilkS")
		)
		(fp_line
			(start -0.7874 0.4064)
			(end -0.7874 -0.4064)
			(stroke
				(width 0.1524)
				(type default)
			)
			(layer "F.SilkS")
		)
		(fp_line
			(start -0.7874 -0.4064)
			(end 0.7874 -0.4064)
			(stroke
				(width 0.1524)
				(type default)
			)
			(layer "F.SilkS")
		)
		(fp_line
			(start 0.67945 0.3048)
			(end 0.120396 0.3048)
			(stroke
				(width 0.1)
				(type default)
			)
			(layer "F.Fab")
		)
		(fp_line
			(start 0.67945 -0.3048)
			(end 0.67945 0.3048)
			(stroke
				(width 0.1)
				(type default)
			)
			(layer "F.Fab")
		)
		(fp_line
			(start 0.12065 -0.2794)
			(end 0.12065 -0.3048)
			(stroke
				(width 0.1)
				(type default)
			)
			(layer "F.Fab")
		)
		(fp_line
			(start 0.12065 -0.3048)
			(end 0.67945 -0.3048)
			(stroke
				(width 0.1)
				(type default)
			)
			(layer "F.Fab")
		)
		(fp_line
			(start 0.120396 0.3048)
			(end 0.120396 0.2794)
			(stroke
				(width 0.1)
				(type default)
			)
			(layer "F.Fab")
		)
		(fp_line
			(start 0.120396 0.2794)
			(end -0.12065 0.2794)
			(stroke
				(width 0.1)
				(type default)
			)
			(layer "F.Fab")
		)
		(fp_line
			(start -0.12065 0.3048)
			(end -0.67945 0.3048)
			(stroke
				(width 0.1)
				(type default)
			)
			(layer "F.Fab")
		)
		(fp_line
			(start -0.12065 0.2794)
			(end -0.12065 0.3048)
			(stroke
				(width 0.1)
				(type default)
			)
			(layer "F.Fab")
		)
		(fp_line
			(start -0.12065 -0.2794)
			(end 0.12065 -0.2794)
			(stroke
				(width 0.1)
				(type default)
			)
			(layer "F.Fab")
		)
		(fp_line
			(start -0.12065 -0.305054)
			(end -0.12065 -0.2794)
			(stroke
				(width 0.1)
				(type default)
			)
			(layer "F.Fab")
		)
		(fp_line
			(start -0.67945 0.3048)
			(end -0.67945 -0.305054)
			(stroke
				(width 0.1)
				(type default)
			)
			(layer "F.Fab")
		)
		(fp_line
			(start -0.67945 -0.305054)
			(end -0.12065 -0.305054)
			(stroke
				(width 0.1)
				(type default)
			)
			(layer "F.Fab")
		)
		(pad "1" smd circle
			(at -0.40005 0 180)
			(size 0 0)
			(layers "F.Cu" "F.Mask" "F.Paste")
			(net "P3V3_AUX")
		)
		(pad "2" smd circle
			(at 0.40005 0 180)
			(size 0 0)
			(layers "F.Cu" "F.Mask" "F.Paste")
			(net "PWR_EN_P3V3_R")
		)
	)
)
